(kicad_pcb
	(version 20260206)
	(generator "pcbnew")
	(generator_version "10.0")
	(general
		(thickness 1.6)
		(legacy_teardrops no)
	)
	(paper "A4")
	(title_block
		(title "03242023_DA0F0TMBIJ0_F0T_Motherboard_J_brd_V01_OCP.brd")
		(comment 1 "Grand Teton / footprints 4930-4935 of 6105")
	)
	(layers
		(0 "F.Cu" signal "TOP")
		(4 "In1.Cu" signal "GND")
		(6 "In2.Cu" signal "IN1")
		(8 "In3.Cu" signal "GND1")
		(10 "In4.Cu" signal "IN2")
		(12 "In5.Cu" signal "GND2")
		(14 "In6.Cu" signal "IN3")
		(16 "In7.Cu" signal "GND3")
		(18 "In8.Cu" signal "VCC")
		(20 "In9.Cu" signal "VCC1")
		(22 "In10.Cu" signal "GND4")
		(24 "In11.Cu" signal "IN4")
		(26 "In12.Cu" signal "GND5")
		(28 "In13.Cu" signal "IN5")
		(30 "In14.Cu" signal "GND6")
		(32 "In15.Cu" signal "IN6")
		(34 "In16.Cu" signal "GND7")
		(2 "B.Cu" signal "BOTTOM")
		(9 "F.Adhes" user "F.Adhesive")
		(11 "B.Adhes" user "B.Adhesive")
		(13 "F.Paste" user "Package Geometry/Pastemask Top")
		(15 "B.Paste" user "Package Geometry/Pastemask Bottom")
		(5 "F.SilkS" user "Ref Des/Silkscreen Top")
		(7 "B.SilkS" user "Ref Des/Silkscreen Bottom")
		(1 "F.Mask" user "Board Geometry/Soldermask Top")
		(3 "B.Mask" user "Board Geometry/Soldermask Bottom")
		(17 "Dwgs.User" user "User.Drawings")
		(19 "Cmts.User" user "User.Comments")
		(21 "Eco1.User" user "User.Eco1")
		(23 "Eco2.User" user "User.Eco2")
		(25 "Edge.Cuts" user "Board Geometry/Outline")
		(27 "Margin" user)
		(31 "F.CrtYd" user "Package Geometry/Place Bound Top")
		(29 "B.CrtYd" user "Package Geometry/Place Bound Bottom")
		(35 "F.Fab" user "Ref Des/Assembly Top")
		(33 "B.Fab" user "Ref Des/Assembly Bottom")
	)
	(footprint ""
		(layer "B.Cu")
		(at 229.89032 -127.922274 180)
		(property "Reference" "R4534"
			(at 0 0 0)
			(layer "B.SilkS")
			(hide yes)
			(effects
				(font
					(size 1.27 1.27)
				)
				(justify mirror)
			)
		)
		(property "Value" ""
			(at 0 0 0)
			(layer "B.Fab")
			(effects
				(font
					(size 1.27 1.27)
				)
				(justify mirror)
			)
		)
		(duplicate_pad_numbers_are_jumpers no)
		(fp_line
			(start 0.7874 0.4064)
			(end 0.7874 -0.4064)
			(stroke
				(width 0.1524)
				(type default)
			)
			(layer "B.SilkS")
		)
		(fp_line
			(start 0.7874 -0.4064)
			(end -0.7874 -0.4064)
			(stroke
				(width 0.1524)
				(type default)
			)
			(layer "B.SilkS")
		)
		(fp_line
			(start -0.7874 0.4064)
			(end 0.7874 0.4064)
			(stroke
				(width 0.1524)
				(type default)
			)
			(layer "B.SilkS")
		)
		(fp_line
			(start -0.7874 -0.4064)
			(end -0.7874 0.4064)
			(stroke
				(width 0.1524)
				(type default)
			)
			(layer "B.SilkS")
		)
		(fp_line
			(start 0.67945 0.3048)
			(end 0.67945 -0.305054)
			(stroke
				(width 0.1)
				(type default)
			)
			(layer "B.Fab")
		)
		(fp_line
			(start 0.67945 -0.305054)
			(end 0.12065 -0.305054)
			(stroke
				(width 0.1)
				(type default)
			)
			(layer "B.Fab")
		)
		(fp_line
			(start 0.12065 0.3048)
			(end 0.67945 0.3048)
			(stroke
				(width 0.1)
				(type default)
			)
			(layer "B.Fab")
		)
		(fp_line
			(start 0.12065 0.2794)
			(end 0.12065 0.3048)
			(stroke
				(width 0.1)
				(type default)
			)
			(layer "B.Fab")
		)
		(fp_line
			(start 0.12065 -0.2794)
			(end -0.12065 -0.2794)
			(stroke
				(width 0.1)
				(type default)
			)
			(layer "B.Fab")
		)
		(fp_line
			(start 0.12065 -0.305054)
			(end 0.12065 -0.2794)
			(stroke
				(width 0.1)
				(type default)
			)
			(layer "B.Fab")
		)
		(fp_line
			(start -0.120396 0.3048)
			(end -0.120396 0.2794)
			(stroke
				(width 0.1)
				(type default)
			)
			(layer "B.Fab")
		)
		(fp_line
			(start -0.120396 0.2794)
			(end 0.12065 0.2794)
			(stroke
				(width 0.1)
				(type default)
			)
			(layer "B.Fab")
		)
		(fp_line
			(start -0.12065 -0.2794)
			(end -0.12065 -0.3048)
			(stroke
				(width 0.1)
				(type default)
			)
			(layer "B.Fab")
		)
		(fp_line
			(start -0.12065 -0.3048)
			(end -0.67945 -0.3048)
			(stroke
				(width 0.1)
				(type default)
			)
			(layer "B.Fab")
		)
		(fp_line
			(start -0.67945 0.3048)
			(end -0.120396 0.3048)
			(stroke
				(width 0.1)
				(type default)
			)
			(layer "B.Fab")
		)
		(fp_line
			(start -0.67945 -0.3048)
			(end -0.67945 0.3048)
			(stroke
				(width 0.1)
				(type default)
			)
			(layer "B.Fab")
		)
		(pad "1" smd circle
			(at 0.40005 0)
			(size 0 0)
			(layers "B.Cu" "B.Mask" "B.Paste")
			(net "CLK_SWB_OE_N")
		)
		(pad "2" smd circle
			(at -0.40005 0)
			(size 0 0)
			(layers "B.Cu" "B.Mask" "B.Paste")
			(net "FM_DB2000_8_OE_N")
		)
	)
	(footprint ""
		(layer "B.Cu")
		(at 85.122004 -186.003692 -90)
		(property "Reference" "R303"
			(at 0 0 90)
			(layer "B.SilkS")
			(hide yes)
			(effects
				(font
					(size 1.27 1.27)
				)
				(justify mirror)
			)
		)
		(property "Value" ""
			(at 0 0 90)
			(layer "B.Fab")
			(effects
				(font
					(size 1.27 1.27)
				)
				(justify mirror)
			)
		)
		(duplicate_pad_numbers_are_jumpers no)
		(fp_line
			(start -0.7874 0.4064)
			(end 0.7874 0.4064)
			(stroke
				(width 0.1524)
				(type default)
			)
			(layer "B.SilkS")
		)
		(fp_line
			(start 0.7874 0.4064)
			(end 0.7874 -0.4064)
			(stroke
				(width 0.1524)
				(type default)
			)
			(layer "B.SilkS")
		)
		(fp_line
			(start -0.7874 -0.4064)
			(end -0.7874 0.4064)
			(stroke
				(width 0.1524)
				(type default)
			)
			(layer "B.SilkS")
		)
		(fp_line
			(start 0.7874 -0.4064)
			(end -0.7874 -0.4064)
			(stroke
				(width 0.1524)
				(type default)
			)
			(layer "B.SilkS")
		)
		(fp_line
			(start -0.67945 0.3048)
			(end -0.120396 0.3048)
			(stroke
				(width 0.1)
				(type default)
			)
			(layer "B.Fab")
		)
		(fp_line
			(start -0.120396 0.3048)
			(end -0.120396 0.2794)
			(stroke
				(width 0.1)
				(type default)
			)
			(layer "B.Fab")
		)
		(fp_line
			(start 0.12065 0.3048)
			(end 0.67945 0.3048)
			(stroke
				(width 0.1)
				(type default)
			)
			(layer "B.Fab")
		)
		(fp_line
			(start 0.67945 0.3048)
			(end 0.67945 -0.305054)
			(stroke
				(width 0.1)
				(type default)
			)
			(layer "B.Fab")
		)
		(fp_line
			(start -0.120396 0.2794)
			(end 0.12065 0.2794)
			(stroke
				(width 0.1)
				(type default)
			)
			(layer "B.Fab")
		)
		(fp_line
			(start 0.12065 0.2794)
			(end 0.12065 0.3048)
			(stroke
				(width 0.1)
				(type default)
			)
			(layer "B.Fab")
		)
		(fp_line
			(start -0.12065 -0.2794)
			(end -0.12065 -0.3048)
			(stroke
				(width 0.1)
				(type default)
			)
			(layer "B.Fab")
		)
		(fp_line
			(start 0.12065 -0.2794)
			(end -0.12065 -0.2794)
			(stroke
				(width 0.1)
				(type default)
			)
			(layer "B.Fab")
		)
		(fp_line
			(start -0.67945 -0.3048)
			(end -0.67945 0.3048)
			(stroke
				(width 0.1)
				(type default)
			)
			(layer "B.Fab")
		)
		(fp_line
			(start -0.12065 -0.3048)
			(end -0.67945 -0.3048)
			(stroke
				(width 0.1)
				(type default)
			)
			(layer "B.Fab")
		)
		(fp_line
			(start 0.12065 -0.305054)
			(end 0.12065 -0.2794)
			(stroke
				(width 0.1)
				(type default)
			)
			(layer "B.Fab")
		)
		(fp_line
			(start 0.67945 -0.305054)
			(end 0.12065 -0.305054)
			(stroke
				(width 0.1)
				(type default)
			)
			(layer "B.Fab")
		)
		(pad "1" smd circle
			(at 0.40005 0 90)
			(size 0 0)
			(layers "B.Cu" "B.Mask" "B.Paste")
			(net "PVNN_TERM_CPU1")
		)
		(pad "2" smd circle
			(at -0.40005 0 90)
			(size 0 0)
			(layers "B.Cu" "B.Mask" "B.Paste")
			(net "H_CPU_RMCA_LVC1_R_N")
		)
	)
	(footprint ""
		(layer "B.Cu")
		(at 406.776428 -257.89001 -90)
		(property "Reference" "C494"
			(at 0 0 90)
			(layer "B.SilkS")
			(hide yes)
			(effects
				(font
					(size 1.27 1.27)
				)
				(justify mirror)
			)
		)
		(property "Value" ""
			(at 0 0 90)
			(layer "B.Fab")
			(effects
				(font
					(size 1.27 1.27)
				)
				(justify mirror)
			)
		)
		(duplicate_pad_numbers_are_jumpers no)
		(fp_line
			(start -1.524 0.762)
			(end 1.524 0.762)
			(stroke
				(width 0.1524)
				(type default)
			)
			(layer "B.SilkS")
		)
		(fp_line
			(start 1.524 0.762)
			(end 1.524 -0.762)
			(stroke
				(width 0.1524)
				(type default)
			)
			(layer "B.SilkS")
		)
		(fp_line
			(start -1.524 -0.762)
			(end -1.524 0.762)
			(stroke
				(width 0.1524)
				(type default)
			)
			(layer "B.SilkS")
		)
		(fp_line
			(start 1.524 -0.762)
			(end -1.524 -0.762)
			(stroke
				(width 0.1524)
				(type default)
			)
			(layer "B.SilkS")
		)
		(fp_line
			(start -1.1049 0.724916)
			(end -1.1049 -0.724916)
			(stroke
				(width 0.1)
				(type default)
			)
			(layer "B.Fab")
		)
		(fp_line
			(start 1.1049 0.724916)
			(end -1.1049 0.724916)
			(stroke
				(width 0.1)
				(type default)
			)
			(layer "B.Fab")
		)
		(fp_line
			(start -1.1049 -0.724916)
			(end 1.1049 -0.724916)
			(stroke
				(width 0.1)
				(type default)
			)
			(layer "B.Fab")
		)
		(fp_line
			(start 1.1049 -0.724916)
			(end 1.1049 0.724916)
			(stroke
				(width 0.1)
				(type default)
			)
			(layer "B.Fab")
		)
		(pad "1" smd rect
			(at 0.889 0 270)
			(size 1.016 1.27)
			(layers "B.Cu" "B.Mask" "B.Paste")
			(net "PVCCFA_EHV_FIVRA_CPU0")
		)
		(pad "2" smd rect
			(at -0.889 0 270)
			(size 1.016 1.27)
			(layers "B.Cu" "B.Mask" "B.Paste")
			(net "GND")
		)
	)
	(footprint ""
		(layer "B.Cu")
		(at 420.682166 -138.333988 180)
		(property "Reference" "PR105"
			(at 0 0 0)
			(layer "B.SilkS")
			(hide yes)
			(effects
				(font
					(size 1.27 1.27)
				)
				(justify mirror)
			)
		)
		(property "Value" ""
			(at 0 0 0)
			(layer "B.Fab")
			(effects
				(font
					(size 1.27 1.27)
				)
				(justify mirror)
			)
		)
		(duplicate_pad_numbers_are_jumpers no)
		(fp_line
			(start 0.7874 0.4064)
			(end 0.7874 -0.4064)
			(stroke
				(width 0.1524)
				(type default)
			)
			(layer "B.SilkS")
		)
		(fp_line
			(start 0.7874 -0.4064)
			(end -0.7874 -0.4064)
			(stroke
				(width 0.1524)
				(type default)
			)
			(layer "B.SilkS")
		)
		(fp_line
			(start -0.7874 0.4064)
			(end 0.7874 0.4064)
			(stroke
				(width 0.1524)
				(type default)
			)
			(layer "B.SilkS")
		)
		(fp_line
			(start -0.7874 -0.4064)
			(end -0.7874 0.4064)
			(stroke
				(width 0.1524)
				(type default)
			)
			(layer "B.SilkS")
		)
		(fp_line
			(start 0.67945 0.3048)
			(end 0.67945 -0.305054)
			(stroke
				(width 0.1)
				(type default)
			)
			(layer "B.Fab")
		)
		(fp_line
			(start 0.67945 -0.305054)
			(end 0.12065 -0.305054)
			(stroke
				(width 0.1)
				(type default)
			)
			(layer "B.Fab")
		)
		(fp_line
			(start 0.12065 0.3048)
			(end 0.67945 0.3048)
			(stroke
				(width 0.1)
				(type default)
			)
			(layer "B.Fab")
		)
		(fp_line
			(start 0.12065 0.2794)
			(end 0.12065 0.3048)
			(stroke
				(width 0.1)
				(type default)
			)
			(layer "B.Fab")
		)
		(fp_line
			(start 0.12065 -0.2794)
			(end -0.12065 -0.2794)
			(stroke
				(width 0.1)
				(type default)
			)
			(layer "B.Fab")
		)
		(fp_line
			(start 0.12065 -0.305054)
			(end 0.12065 -0.2794)
			(stroke
				(width 0.1)
				(type default)
			)
			(layer "B.Fab")
		)
		(fp_line
			(start -0.120396 0.3048)
			(end -0.120396 0.2794)
			(stroke
				(width 0.1)
				(type default)
			)
			(layer "B.Fab")
		)
		(fp_line
			(start -0.120396 0.2794)
			(end 0.12065 0.2794)
			(stroke
				(width 0.1)
				(type default)
			)
			(layer "B.Fab")
		)
		(fp_line
			(start -0.12065 -0.2794)
			(end -0.12065 -0.3048)
			(stroke
				(width 0.1)
				(type default)
			)
			(layer "B.Fab")
		)
		(fp_line
			(start -0.12065 -0.3048)
			(end -0.67945 -0.3048)
			(stroke
				(width 0.1)
				(type default)
			)
			(layer "B.Fab")
		)
		(fp_line
			(start -0.67945 0.3048)
			(end -0.120396 0.3048)
			(stroke
				(width 0.1)
				(type default)
			)
			(layer "B.Fab")
		)
		(fp_line
			(start -0.67945 -0.3048)
			(end -0.67945 0.3048)
			(stroke
				(width 0.1)
				(type default)
			)
			(layer "B.Fab")
		)
		(pad "1" smd circle
			(at 0.40005 0)
			(size 0 0)
			(layers "B.Cu" "B.Mask" "B.Paste")
			(net "PVCCINFAON_CPU0_VREF")
		)
		(pad "2" smd circle
			(at -0.40005 0)
			(size 0 0)
			(layers "B.Cu" "B.Mask" "B.Paste")
			(net "PVCCINFAON_CPU0_ADDR")
		)
	)
	(footprint ""
		(layer "B.Cu")
		(at 160.83788 -107.025948 180)
		(property "Reference" "R3203"
			(at 0 0 0)
			(layer "B.SilkS")
			(hide yes)
			(effects
				(font
					(size 1.27 1.27)
				)
				(justify mirror)
			)
		)
		(property "Value" ""
			(at 0 0 0)
			(layer "B.Fab")
			(effects
				(font
					(size 1.27 1.27)
				)
				(justify mirror)
			)
		)
		(duplicate_pad_numbers_are_jumpers no)
		(fp_line
			(start 0.7874 0.4064)
			(end 0.7874 -0.4064)
			(stroke
				(width 0.1524)
				(type default)
			)
			(layer "B.SilkS")
		)
		(fp_line
			(start 0.7874 -0.4064)
			(end -0.7874 -0.4064)
			(stroke
				(width 0.1524)
				(type default)
			)
			(layer "B.SilkS")
		)
		(fp_line
			(start -0.7874 0.4064)
			(end 0.7874 0.4064)
			(stroke
				(width 0.1524)
				(type default)
			)
			(layer "B.SilkS")
		)
		(fp_line
			(start -0.7874 -0.4064)
			(end -0.7874 0.4064)
			(stroke
				(width 0.1524)
				(type default)
			)
			(layer "B.SilkS")
		)
		(fp_line
			(start 0.67945 0.3048)
			(end 0.67945 -0.305054)
			(stroke
				(width 0.1)
				(type default)
			)
			(layer "B.Fab")
		)
		(fp_line
			(start 0.67945 -0.305054)
			(end 0.12065 -0.305054)
			(stroke
				(width 0.1)
				(type default)
			)
			(layer "B.Fab")
		)
		(fp_line
			(start 0.12065 0.3048)
			(end 0.67945 0.3048)
			(stroke
				(width 0.1)
				(type default)
			)
			(layer "B.Fab")
		)
		(fp_line
			(start 0.12065 0.2794)
			(end 0.12065 0.3048)
			(stroke
				(width 0.1)
				(type default)
			)
			(layer "B.Fab")
		)
		(fp_line
			(start 0.12065 -0.2794)
			(end -0.12065 -0.2794)
			(stroke
				(width 0.1)
				(type default)
			)
			(layer "B.Fab")
		)
		(fp_line
			(start 0.12065 -0.305054)
			(end 0.12065 -0.2794)
			(stroke
				(width 0.1)
				(type default)
			)
			(layer "B.Fab")
		)
		(fp_line
			(start -0.120396 0.3048)
			(end -0.120396 0.2794)
			(stroke
				(width 0.1)
				(type default)
			)
			(layer "B.Fab")
		)
		(fp_line
			(start -0.120396 0.2794)
			(end 0.12065 0.2794)
			(stroke
				(width 0.1)
				(type default)
			)
			(layer "B.Fab")
		)
		(fp_line
			(start -0.12065 -0.2794)
			(end -0.12065 -0.3048)
			(stroke
				(width 0.1)
				(type default)
			)
			(layer "B.Fab")
		)
		(fp_line
			(start -0.12065 -0.3048)
			(end -0.67945 -0.3048)
			(stroke
				(width 0.1)
				(type default)
			)
			(layer "B.Fab")
		)
		(fp_line
			(start -0.67945 0.3048)
			(end -0.120396 0.3048)
			(stroke
				(width 0.1)
				(type default)
			)
			(layer "B.Fab")
		)
		(fp_line
			(start -0.67945 -0.3048)
			(end -0.67945 0.3048)
			(stroke
				(width 0.1)
				(type default)
			)
			(layer "B.Fab")
		)
		(pad "1" smd circle
			(at 0.40005 0)
			(size 0 0)
			(layers "B.Cu" "B.Mask" "B.Paste")
			(net "OCP_V3_2_AUX_PWR_EN")
		)
		(pad "2" smd circle
			(at -0.40005 0)
			(size 0 0)
			(layers "B.Cu" "B.Mask" "B.Paste")
			(net "OCP_V3_2_AUX_PWR_EN_R1")
		)
	)
	(footprint ""
		(layer "B.Cu")
		(at 292.980618 -149.992588 90)
		(property "Reference" "R318"
			(at 0 0 90)
			(layer "B.SilkS")
			(hide yes)
			(effects
				(font
					(size 1.27 1.27)
				)
				(justify mirror)
			)
		)
		(property "Value" ""
			(at 0 0 90)
			(layer "B.Fab")
			(effects
				(font
					(size 1.27 1.27)
				)
				(justify mirror)
			)
		)
		(duplicate_pad_numbers_are_jumpers no)
		(fp_line
			(start 0.7874 -0.4064)
			(end -0.7874 -0.4064)
			(stroke
				(width 0.1524)
				(type default)
			)
			(layer "B.SilkS")
		)
		(fp_line
			(start -0.7874 -0.4064)
			(end -0.7874 0.4064)
			(stroke
				(width 0.1524)
				(type default)
			)
			(layer "B.SilkS")
		)
		(fp_line
			(start 0.7874 0.4064)
			(end 0.7874 -0.4064)
			(stroke
				(width 0.1524)
				(type default)
			)
			(layer "B.SilkS")
		)
		(fp_line
			(start -0.7874 0.4064)
			(end 0.7874 0.4064)
			(stroke
				(width 0.1524)
				(type default)
			)
			(layer "B.SilkS")
		)
		(fp_line
			(start 0.67945 -0.305054)
			(end 0.12065 -0.305054)
			(stroke
				(width 0.1)
				(type default)
			)
			(layer "B.Fab")
		)
		(fp_line
			(start 0.12065 -0.305054)
			(end 0.12065 -0.2794)
			(stroke
				(width 0.1)
				(type default)
			)
			(layer "B.Fab")
		)
		(fp_line
			(start -0.12065 -0.3048)
			(end -0.67945 -0.3048)
			(stroke
				(width 0.1)
				(type default)
			)
			(layer "B.Fab")
		)
		(fp_line
			(start -0.67945 -0.3048)
			(end -0.67945 0.3048)
			(stroke
				(width 0.1)
				(type default)
			)
			(layer "B.Fab")
		)
		(fp_line
			(start 0.12065 -0.2794)
			(end -0.12065 -0.2794)
			(stroke
				(width 0.1)
				(type default)
			)
			(layer "B.Fab")
		)
		(fp_line
			(start -0.12065 -0.2794)
			(end -0.12065 -0.3048)
			(stroke
				(width 0.1)
				(type default)
			)
			(layer "B.Fab")
		)
		(fp_line
			(start 0.12065 0.2794)
			(end 0.12065 0.3048)
			(stroke
				(width 0.1)
				(type default)
			)
			(layer "B.Fab")
		)
		(fp_line
			(start -0.120396 0.2794)
			(end 0.12065 0.2794)
			(stroke
				(width 0.1)
				(type default)
			)
			(layer "B.Fab")
		)
		(fp_line
			(start 0.67945 0.3048)
			(end 0.67945 -0.305054)
			(stroke
				(width 0.1)
				(type default)
			)
			(layer "B.Fab")
		)
		(fp_line
			(start 0.12065 0.3048)
			(end 0.67945 0.3048)
			(stroke
				(width 0.1)
				(type default)
			)
			(layer "B.Fab")
		)
		(fp_line
			(start -0.120396 0.3048)
			(end -0.120396 0.2794)
			(stroke
				(width 0.1)
				(type default)
			)
			(layer "B.Fab")
		)
		(fp_line
			(start -0.67945 0.3048)
			(end -0.120396 0.3048)
			(stroke
				(width 0.1)
				(type default)
			)
			(layer "B.Fab")
		)
		(pad "1" smd circle
			(at 0.40005 0 270)
			(size 0 0)
			(layers "B.Cu" "B.Mask" "B.Paste")
			(net "FM_SPD_REMOTE_EN")
		)
		(pad "2" smd circle
			(at -0.40005 0 270)
			(size 0 0)
			(layers "B.Cu" "B.Mask" "B.Paste")
			(net "GND")
		)
	)
)
